(kicad_pcb
	(version 20260206)
	(generator "pcbnew")
	(generator_version "10.0")
	(general
		(thickness 1.6)
		(legacy_teardrops no)
	)
	(paper "A4")
	(title_block
		(title "Wiwynn_Tioga_Pass_MB.brd")
		(comment 1 "Tioga Pass / footprint 1441 of 4770 (J4G3), pads 244-291 of 291")
	)
	(layers
		(0 "F.Cu" signal "TOP")
		(4 "In1.Cu" signal "L2GND")
		(6 "In2.Cu" signal "L3")
		(8 "In3.Cu" signal "L4GND")
		(10 "In4.Cu" signal "L5")
		(12 "In5.Cu" signal "L6GND")
		(14 "In6.Cu" signal "L7VCC")
		(16 "In7.Cu" signal "L8VCC")
		(18 "In8.Cu" signal "L9GND")
		(20 "In9.Cu" signal "L10")
		(22 "In10.Cu" signal "L11GND")
		(24 "In11.Cu" signal "L12")
		(26 "In12.Cu" signal "L13GND")
		(2 "B.Cu" signal "BOTTOM")
		(9 "F.Adhes" user "F.Adhesive")
		(11 "B.Adhes" user "B.Adhesive")
		(13 "F.Paste" user "Package Geometry/Pastemask Top")
		(15 "B.Paste" user "Package Geometry/Pastemask Bottom")
		(5 "F.SilkS" user "Ref Des/Silkscreen Top")
		(7 "B.SilkS" user "Ref Des/Silkscreen Bottom")
		(1 "F.Mask" user "Board Geometry/Soldermask Top")
		(3 "B.Mask" user "Board Geometry/Soldermask Bottom")
		(17 "Dwgs.User" user "User.Drawings")
		(19 "Cmts.User" user "User.Comments")
		(21 "Eco1.User" user "User.Eco1")
		(23 "Eco2.User" user "User.Eco2")
		(25 "Edge.Cuts" user "Board Geometry/Outline")
		(27 "Margin" user)
		(31 "F.CrtYd" user "Package Geometry/Place Bound Top")
		(29 "B.CrtYd" user "Package Geometry/Place Bound Bottom")
		(35 "F.Fab" user "Ref Des/Assembly Top")
		(33 "B.Fab" user "Ref Des/Assembly Bottom")
	)
	(footprint ""
		(layer "F.Cu")
		(at 194.700398 3.778758 90)
		(property "Reference" "J4G3"
			(at 6.800088 37.20211 0)
			(unlocked yes)
			(layer "F.SilkS")
			(effects
				(font
					(size 0.7874 0.5842)
					(thickness 0.1524)
				)
				(justify left)
			)
		)
		(property "Value" ""
			(at 0 0 90)
			(layer "F.Fab")
			(effects
				(font
					(size 1.27 1.27)
				)
			)
		)
		(duplicate_pad_numbers_are_jumpers no)
		(pad "241" smd rect
			(at 4.59994 86.700106 90)
			(size 1.8034 0.508)
			(layers "F.Cu" "F.Mask" "F.Paste")
			(net "GND")
		)
		(pad "242" smd rect
			(at 4.59994 87.54999 90)
			(size 1.8034 0.508)
			(layers "F.Cu" "F.Mask" "F.Paste")
			(net "M_C_DQ<32>")
		)
		(pad "243" smd rect
			(at 4.59994 88.399874 90)
			(size 1.8034 0.508)
			(layers "F.Cu" "F.Mask" "F.Paste")
			(net "GND")
		)
		(pad "244" smd rect
			(at 4.59994 89.250012 90)
			(size 1.8034 0.508)
			(layers "F.Cu" "F.Mask" "F.Paste")
			(net "M_C_DQS_DN<4>")
		)
		(pad "245" smd rect
			(at 4.59994 90.099896 90)
			(size 1.8034 0.508)
			(layers "F.Cu" "F.Mask" "F.Paste")
			(net "M_C_DQS_DP<4>")
		)
		(pad "246" smd rect
			(at 4.59994 90.950034 90)
			(size 1.8034 0.508)
			(layers "F.Cu" "F.Mask" "F.Paste")
			(net "GND")
		)
		(pad "247" smd rect
			(at 4.59994 91.799918 90)
			(size 1.8034 0.508)
			(layers "F.Cu" "F.Mask" "F.Paste")
			(net "M_C_DQ<38>")
		)
		(pad "248" smd rect
			(at 4.59994 92.650056 90)
			(size 1.8034 0.508)
			(layers "F.Cu" "F.Mask" "F.Paste")
			(net "GND")
		)
		(pad "249" smd rect
			(at 4.59994 93.49994 90)
			(size 1.8034 0.508)
			(layers "F.Cu" "F.Mask" "F.Paste")
			(net "M_C_DQ<34>")
		)
		(pad "250" smd rect
			(at 4.59994 94.350078 90)
			(size 1.8034 0.508)
			(layers "F.Cu" "F.Mask" "F.Paste")
			(net "GND")
		)
		(pad "251" smd rect
			(at 4.59994 95.199962 90)
			(size 1.8034 0.508)
			(layers "F.Cu" "F.Mask" "F.Paste")
			(net "M_C_DQ<44>")
		)
		(pad "252" smd rect
			(at 4.59994 96.0501 90)
			(size 1.8034 0.508)
			(layers "F.Cu" "F.Mask" "F.Paste")
			(net "GND")
		)
		(pad "253" smd rect
			(at 4.59994 96.899984 90)
			(size 1.8034 0.508)
			(layers "F.Cu" "F.Mask" "F.Paste")
			(net "M_C_DQ<40>")
		)
		(pad "254" smd rect
			(at 4.59994 97.750122 90)
			(size 1.8034 0.508)
			(layers "F.Cu" "F.Mask" "F.Paste")
			(net "GND")
		)
		(pad "255" smd rect
			(at 4.59994 98.600006 90)
			(size 1.8034 0.508)
			(layers "F.Cu" "F.Mask" "F.Paste")
			(net "M_C_DQS_DN<5>")
		)
		(pad "256" smd rect
			(at 4.59994 99.44989 90)
			(size 1.8034 0.508)
			(layers "F.Cu" "F.Mask" "F.Paste")
			(net "M_C_DQS_DP<5>")
		)
		(pad "257" smd rect
			(at 4.59994 100.300028 90)
			(size 1.8034 0.508)
			(layers "F.Cu" "F.Mask" "F.Paste")
			(net "GND")
		)
		(pad "258" smd rect
			(at 4.59994 101.149912 90)
			(size 1.8034 0.508)
			(layers "F.Cu" "F.Mask" "F.Paste")
			(net "M_C_DQ<46>")
		)
		(pad "259" smd rect
			(at 4.59994 102.00005 90)
			(size 1.8034 0.508)
			(layers "F.Cu" "F.Mask" "F.Paste")
			(net "GND")
		)
		(pad "260" smd rect
			(at 4.59994 102.849934 90)
			(size 1.8034 0.508)
			(layers "F.Cu" "F.Mask" "F.Paste")
			(net "M_C_DQ<42>")
		)
		(pad "261" smd rect
			(at 4.59994 103.700072 90)
			(size 1.8034 0.508)
			(layers "F.Cu" "F.Mask" "F.Paste")
			(net "GND")
		)
		(pad "262" smd rect
			(at 4.59994 104.549956 90)
			(size 1.8034 0.508)
			(layers "F.Cu" "F.Mask" "F.Paste")
			(net "M_C_DQ<52>")
		)
		(pad "263" smd rect
			(at 4.59994 105.400094 90)
			(size 1.8034 0.508)
			(layers "F.Cu" "F.Mask" "F.Paste")
			(net "GND")
		)
		(pad "264" smd rect
			(at 4.59994 106.249978 90)
			(size 1.8034 0.508)
			(layers "F.Cu" "F.Mask" "F.Paste")
			(net "M_C_DQ<48>")
		)
		(pad "265" smd rect
			(at 4.59994 107.100116 90)
			(size 1.8034 0.508)
			(layers "F.Cu" "F.Mask" "F.Paste")
			(net "GND")
		)
		(pad "266" smd rect
			(at 4.59994 107.95 90)
			(size 1.8034 0.508)
			(layers "F.Cu" "F.Mask" "F.Paste")
			(net "M_C_DQS_DN<6>")
		)
		(pad "267" smd rect
			(at 4.59994 108.799884 90)
			(size 1.8034 0.508)
			(layers "F.Cu" "F.Mask" "F.Paste")
			(net "M_C_DQS_DP<6>")
		)
		(pad "268" smd rect
			(at 4.59994 109.650022 90)
			(size 1.8034 0.508)
			(layers "F.Cu" "F.Mask" "F.Paste")
			(net "GND")
		)
		(pad "269" smd rect
			(at 4.59994 110.499906 90)
			(size 1.8034 0.508)
			(layers "F.Cu" "F.Mask" "F.Paste")
			(net "M_C_DQ<54>")
		)
		(pad "270" smd rect
			(at 4.59994 111.350044 90)
			(size 1.8034 0.508)
			(layers "F.Cu" "F.Mask" "F.Paste")
			(net "GND")
		)
		(pad "271" smd rect
			(at 4.59994 112.199928 90)
			(size 1.8034 0.508)
			(layers "F.Cu" "F.Mask" "F.Paste")
			(net "M_C_DQ<50>")
		)
		(pad "272" smd rect
			(at 4.59994 113.050066 90)
			(size 1.8034 0.508)
			(layers "F.Cu" "F.Mask" "F.Paste")
			(net "GND")
		)
		(pad "273" smd rect
			(at 4.59994 113.89995 90)
			(size 1.8034 0.508)
			(layers "F.Cu" "F.Mask" "F.Paste")
			(net "M_C_DQ<60>")
		)
		(pad "274" smd rect
			(at 4.59994 114.750088 90)
			(size 1.8034 0.508)
			(layers "F.Cu" "F.Mask" "F.Paste")
			(net "GND")
		)
		(pad "275" smd rect
			(at 4.59994 115.599972 90)
			(size 1.8034 0.508)
			(layers "F.Cu" "F.Mask" "F.Paste")
			(net "M_C_DQ<56>")
		)
		(pad "276" smd rect
			(at 4.59994 116.45011 90)
			(size 1.8034 0.508)
			(layers "F.Cu" "F.Mask" "F.Paste")
			(net "GND")
		)
		(pad "277" smd rect
			(at 4.59994 117.299994 90)
			(size 1.8034 0.508)
			(layers "F.Cu" "F.Mask" "F.Paste")
			(net "M_C_DQS_DN<7>")
		)
		(pad "278" smd rect
			(at 4.59994 118.149878 90)
			(size 1.8034 0.508)
			(layers "F.Cu" "F.Mask" "F.Paste")
			(net "M_C_DQS_DP<7>")
		)
		(pad "279" smd rect
			(at 4.59994 119.000016 90)
			(size 1.8034 0.508)
			(layers "F.Cu" "F.Mask" "F.Paste")
			(net "GND")
		)
		(pad "280" smd rect
			(at 4.59994 119.8499 90)
			(size 1.8034 0.508)
			(layers "F.Cu" "F.Mask" "F.Paste")
			(net "M_C_DQ<62>")
		)
		(pad "281" smd rect
			(at 4.59994 120.700038 90)
			(size 1.8034 0.508)
			(layers "F.Cu" "F.Mask" "F.Paste")
			(net "GND")
		)
		(pad "282" smd rect
			(at 4.59994 121.549922 90)
			(size 1.8034 0.508)
			(layers "F.Cu" "F.Mask" "F.Paste")
			(net "M_C_DQ<58>")
		)
		(pad "283" smd rect
			(at 4.59994 122.40006 90)
			(size 1.8034 0.508)
			(layers "F.Cu" "F.Mask" "F.Paste")
			(net "GND")
		)
		(pad "284" smd rect
			(at 4.59994 123.249944 90)
			(size 1.8034 0.508)
			(layers "F.Cu" "F.Mask" "F.Paste")
			(net "PVPP_ABC")
		)
		(pad "285" smd rect
			(at 4.59994 124.100082 90)
			(size 1.8034 0.508)
			(layers "F.Cu" "F.Mask" "F.Paste")
			(net "SMB_DDR_ABC_VPP_SDA")
		)
		(pad "286" smd rect
			(at 4.59994 124.949966 90)
			(size 1.8034 0.508)
			(layers "F.Cu" "F.Mask" "F.Paste")
			(net "PVPP_ABC")
		)
		(pad "287" smd rect
			(at 4.59994 125.800104 90)
			(size 1.8034 0.508)
			(layers "F.Cu" "F.Mask" "F.Paste")
			(net "PVPP_ABC")
		)
		(pad "288" smd rect
			(at 4.59994 126.649988 90)
			(size 1.8034 0.508)
			(layers "F.Cu" "F.Mask" "F.Paste")
			(net "PVPP_ABC")
		)
	)
)
